(kicad_pcb
	(version 20260206)
	(generator "pcbnew")
	(generator_version "10.0")
	(general
		(thickness 1.6)
		(legacy_teardrops no)
	)
	(paper "A4")
	(title_block
		(title "Bryce Canyon_IOM_IOC_16318-2_OCP.brd")
		(comment 1 "Bryce Canyon / footprints 68-74 of 1605")
	)
	(layers
		(0 "F.Cu" signal "TOP")
		(4 "In1.Cu" signal "L2GND")
		(6 "In2.Cu" signal "L3")
		(8 "In3.Cu" signal "L4VCC")
		(10 "In4.Cu" signal "L5VCC")
		(12 "In5.Cu" signal "L6")
		(14 "In6.Cu" signal "L7GND")
		(2 "B.Cu" signal "BOTTOM")
		(9 "F.Adhes" user "F.Adhesive")
		(11 "B.Adhes" user "B.Adhesive")
		(13 "F.Paste" user "Package Geometry/Pastemask Top")
		(15 "B.Paste" user "Package Geometry/Pastemask Bottom")
		(5 "F.SilkS" user "Ref Des/Silkscreen Top")
		(7 "B.SilkS" user "Ref Des/Silkscreen Bottom")
		(1 "F.Mask" user "Board Geometry/Soldermask Top")
		(3 "B.Mask" user "Board Geometry/Soldermask Bottom")
		(17 "Dwgs.User" user "User.Drawings")
		(19 "Cmts.User" user "User.Comments")
		(21 "Eco1.User" user "User.Eco1")
		(23 "Eco2.User" user "User.Eco2")
		(25 "Edge.Cuts" user "Board Geometry/Outline")
		(27 "Margin" user)
		(31 "F.CrtYd" user "Package Geometry/Place Bound Top")
		(29 "B.CrtYd" user "Package Geometry/Place Bound Bottom")
		(35 "F.Fab" user "Ref Des/Assembly Top")
		(33 "B.Fab" user "Ref Des/Assembly Bottom")
	)
	(footprint ""
		(layer "F.Cu")
		(at 150.876 -38.481)
		(property "Reference" "TP180"
			(at 0 0 0)
			(layer "F.SilkS")
			(hide yes)
			(effects
				(font
					(size 1.27 1.27)
				)
			)
		)
		(property "Value" "TPAD28-2-GP"
			(at -0.0127 -1.6637 0)
			(unlocked yes)
			(layer "F.Fab")
			(hide yes)
			(effects
				(font
					(size 1.016 1.016)
					(thickness 0.1524)
				)
			)
		)
		(property "Device Type" "TPAD28"
			(at -0.0127 -3.1877 0)
			(unlocked yes)
			(layer "F.Fab")
			(hide yes)
			(effects
				(font
					(size 1.016 1.016)
					(thickness 0.1524)
				)
			)
		)
		(duplicate_pad_numbers_are_jumpers no)
		(fp_poly
			(pts
				(arc
					(start 0.3556 0)
					(mid -0.3556 0)
					(end 0.3556 0)
				)
			)
			(stroke
				(width 0)
				(type default)
			)
			(fill no)
			(layer "F.CrtYd")
		)
		(fp_poly
			(pts
				(arc
					(start 0.6096 0)
					(mid -0.6096 0)
					(end 0.6096 0)
				)
			)
			(stroke
				(width 0)
				(type default)
			)
			(fill no)
			(layer "F.Fab")
		)
		(pad "1" smd circle
			(at 0 0)
			(size 0.7112 0.7112)
			(layers "F.Cu" "F.Mask" "F.Paste")
			(net "ZDEF_EXTB_TP_A2")
		)
	)
	(footprint ""
		(layer "F.Cu")
		(at 97.9424 -135.6868)
		(property "Reference" "R139"
			(at 0 0 0)
			(layer "F.SilkS")
			(hide yes)
			(effects
				(font
					(size 1.27 1.27)
				)
			)
		)
		(property "Value" "8K2R2J-3-GP"
			(at 0.064008 -3.993896 0)
			(unlocked yes)
			(layer "F.Fab")
			(hide yes)
			(effects
				(font
					(size 1.016 1.016)
					(thickness 0.1524)
				)
			)
		)
		(property "Device Type" "R402H16"
			(at 0.064008 -5.517896 0)
			(unlocked yes)
			(layer "F.Fab")
			(hide yes)
			(effects
				(font
					(size 1.016 1.016)
					(thickness 0.1524)
				)
			)
		)
		(duplicate_pad_numbers_are_jumpers no)
		(fp_line
			(start -0.508 -0.9398)
			(end -0.508 0.9398)
			(stroke
				(width 0.1524)
				(type default)
			)
			(layer "F.SilkS")
		)
		(fp_line
			(start 0.508 -0.9398)
			(end -0.508 -0.9398)
			(stroke
				(width 0.1524)
				(type default)
			)
			(layer "F.SilkS")
		)
		(fp_rect
			(start -0.508 0.9398)
			(end 0.508 -0.9398)
			(stroke
				(width 0)
				(type default)
			)
			(fill no)
			(layer "F.CrtYd")
		)
		(fp_rect
			(start -0.508 0.9398)
			(end 0.508 -0.9398)
			(stroke
				(width 0)
				(type default)
			)
			(fill no)
			(layer "F.Fab")
		)
		(pad "1" smd custom
			(at 0 -0.4445)
			(size 0.1397 0.1397)
			(layers "F.Cu" "F.Mask" "F.Paste")
			(net "EEPROM_WP")
			(options
				(clearance outline)
				(anchor circle)
			)
			(primitives
				(gr_poly
					(pts
						(arc
							(start -0.1778 -0.2794)
							(mid -0.249642 -0.249642)
							(end -0.2794 -0.1778)
						)
						(arc
							(start -0.2794 0.1778)
							(mid -0.249642 0.249642)
							(end -0.1778 0.2794)
						)
						(arc
							(start 0.1778 0.2794)
							(mid 0.249642 0.249642)
							(end 0.2794 0.1778)
						)
						(arc
							(start 0.2794 -0.1778)
							(mid 0.249642 -0.249642)
							(end 0.1778 -0.2794)
						)
					)
					(width 0)
					(fill yes)
				)
			)
		)
		(pad "2" smd custom
			(at 0 0.4445)
			(size 0.1397 0.1397)
			(layers "F.Cu" "F.Mask" "F.Paste")
			(net "GND")
			(options
				(clearance outline)
				(anchor circle)
			)
			(primitives
				(gr_poly
					(pts
						(arc
							(start -0.1778 -0.2794)
							(mid -0.249642 -0.249642)
							(end -0.2794 -0.1778)
						)
						(arc
							(start -0.2794 0.1778)
							(mid -0.249642 0.249642)
							(end -0.1778 0.2794)
						)
						(arc
							(start 0.1778 0.2794)
							(mid 0.249642 0.249642)
							(end 0.2794 0.1778)
						)
						(arc
							(start 0.2794 -0.1778)
							(mid 0.249642 -0.249642)
							(end 0.1778 -0.2794)
						)
					)
					(width 0)
					(fill yes)
				)
			)
		)
	)
	(footprint ""
		(layer "F.Cu")
		(at 93.748352 -134.411974 -90)
		(property "Reference" "U26"
			(at 0 0 270)
			(layer "F.SilkS")
			(hide yes)
			(effects
				(font
					(size 1.27 1.27)
				)
			)
		)
		(property "Value" "24LC64-I-SN-GP"
			(at -3.707384 -1.5367 270)
			(unlocked yes)
			(layer "F.Fab")
			(hide yes)
			(effects
				(font
					(size 1.016 1.016)
					(thickness 0.1524)
				)
			)
		)
		(property "Device Type" "SOIC8H69"
			(at -3.707384 -3.0607 270)
			(unlocked yes)
			(layer "F.Fab")
			(hide yes)
			(effects
				(font
					(size 1.016 1.016)
					(thickness 0.1524)
				)
			)
		)
		(duplicate_pad_numbers_are_jumpers no)
		(fp_line
			(start -2.6289 3.4417)
			(end -2.6289 1.4732)
			(stroke
				(width 0.381)
				(type default)
			)
			(layer "F.SilkS")
		)
		(fp_line
			(start -2.7432 1.4224)
			(end -2.6416 1.4224)
			(stroke
				(width 0.1524)
				(type default)
			)
			(layer "F.SilkS")
		)
		(fp_line
			(start -2.7432 1.4224)
			(end 2.1336 1.4224)
			(stroke
				(width 0.1524)
				(type default)
			)
			(layer "F.SilkS")
		)
		(fp_line
			(start 2.1336 1.4224)
			(end 2.1336 -1.4224)
			(stroke
				(width 0.1524)
				(type default)
			)
			(layer "F.SilkS")
		)
		(fp_line
			(start -2.1844 -0.0508)
			(end -2.7178 0.508)
			(stroke
				(width 0.1524)
				(type default)
			)
			(layer "F.SilkS")
		)
		(fp_line
			(start -2.7178 -0.508)
			(end -2.1844 -0.0508)
			(stroke
				(width 0.1524)
				(type default)
			)
			(layer "F.SilkS")
		)
		(fp_line
			(start -2.7432 -1.4224)
			(end -2.7432 1.4224)
			(stroke
				(width 0.1524)
				(type default)
			)
			(layer "F.SilkS")
		)
		(fp_line
			(start 2.1336 -1.4224)
			(end -2.7432 -1.4224)
			(stroke
				(width 0.1524)
				(type default)
			)
			(layer "F.SilkS")
		)
		(fp_poly
			(pts
				(xy -2.2098 -1.4224) (xy -2.2098 1.4224) (xy 2.2098 1.4224) (xy 2.2098 -1.4224)
			)
			(stroke
				(width 0)
				(type default)
			)
			(fill yes)
			(layer "F.SilkS")
		)
		(fp_rect
			(start -2.450084 2.999994)
			(end 2.450084 -2.999994)
			(stroke
				(width 0)
				(type default)
			)
			(fill no)
			(layer "F.CrtYd")
		)
		(fp_poly
			(pts
				(xy -2.8194 3.6322) (xy -2.8194 -3.6322) (xy 2.8194 -3.6322) (xy 2.8194 1.18364) (xy 2.450084 1.18364)
				(xy 2.450084 -2.999994) (xy -2.450084 -2.999994) (xy -2.450084 2.999994) (xy 2.450084 2.999994)
				(xy 2.450084 1.18618) (xy 2.8194 1.18618) (xy 2.8194 3.6322)
			)
			(stroke
				(width 0)
				(type default)
			)
			(fill no)
			(layer "F.CrtYd")
		)
		(fp_rect
			(start -2.8194 3.6322)
			(end 2.8194 -3.6322)
			(stroke
				(width 0)
				(type default)
			)
			(fill no)
			(layer "F.Fab")
		)
		(pad "1" smd rect
			(at -1.905 2.54 270)
			(size 0.635 1.651)
			(layers "F.Cu" "F.Mask" "F.Paste")
			(net "EEPROM_A0")
		)
		(pad "2" smd rect
			(at -0.635 2.54 270)
			(size 0.635 1.651)
			(layers "F.Cu" "F.Mask" "F.Paste")
			(net "EEPROM_A1")
		)
		(pad "3" smd rect
			(at 0.635 2.54 270)
			(size 0.635 1.651)
			(layers "F.Cu" "F.Mask" "F.Paste")
			(net "EEPROM_A2")
		)
		(pad "4" smd rect
			(at 1.905 2.54 270)
			(size 0.635 1.651)
			(layers "F.Cu" "F.Mask" "F.Paste")
			(net "GND")
		)
		(pad "5" smd rect
			(at 1.905 -2.54 270)
			(size 0.635 1.651)
			(layers "F.Cu" "F.Mask" "F.Paste")
			(net "I2C_IOM_SDA")
		)
		(pad "6" smd rect
			(at 0.635 -2.54 270)
			(size 0.635 1.651)
			(layers "F.Cu" "F.Mask" "F.Paste")
			(net "I2C_IOM_SCL")
		)
		(pad "7" smd rect
			(at -0.635 -2.54 270)
			(size 0.635 1.651)
			(layers "F.Cu" "F.Mask" "F.Paste")
			(net "EEPROM_WP")
		)
		(pad "8" smd rect
			(at -1.905 -2.54 270)
			(size 0.635 1.651)
			(layers "F.Cu" "F.Mask" "F.Paste")
			(net "P3V3_STBY")
		)
	)
	(footprint ""
		(layer "F.Cu")
		(at 61.6458 -131.29768 180)
		(property "Reference" "R708"
			(at 0 0 180)
			(layer "F.SilkS")
			(hide yes)
			(effects
				(font
					(size 1.27 1.27)
				)
			)
		)
		(property "Value" "10KR2F-2-GP"
			(at 0.064008 -3.993896 180)
			(unlocked yes)
			(layer "F.Fab")
			(hide yes)
			(effects
				(font
					(size 1.016 1.016)
					(thickness 0.1524)
				)
			)
		)
		(property "Device Type" "R402H16"
			(at 0.064008 -5.517896 180)
			(unlocked yes)
			(layer "F.Fab")
			(hide yes)
			(effects
				(font
					(size 1.016 1.016)
					(thickness 0.1524)
				)
			)
		)
		(duplicate_pad_numbers_are_jumpers no)
		(fp_line
			(start 0.508 -0.9398)
			(end -0.508 -0.9398)
			(stroke
				(width 0.1524)
				(type default)
			)
			(layer "F.SilkS")
		)
		(fp_line
			(start -0.508 -0.9398)
			(end -0.508 0.9398)
			(stroke
				(width 0.1524)
				(type default)
			)
			(layer "F.SilkS")
		)
		(fp_rect
			(start -0.508 0.9398)
			(end 0.508 -0.9398)
			(stroke
				(width 0)
				(type default)
			)
			(fill no)
			(layer "F.CrtYd")
		)
		(fp_rect
			(start -0.508 0.9398)
			(end 0.508 -0.9398)
			(stroke
				(width 0)
				(type default)
			)
			(fill no)
			(layer "F.Fab")
		)
		(pad "1" smd custom
			(at 0 -0.4445 180)
			(size 0.1397 0.1397)
			(layers "F.Cu" "F.Mask" "F.Paste")
			(net "SCC_STBY_PWR_EN")
			(options
				(clearance outline)
				(anchor circle)
			)
			(primitives
				(gr_poly
					(pts
						(arc
							(start -0.1778 -0.2794)
							(mid -0.249642 -0.249642)
							(end -0.2794 -0.1778)
						)
						(arc
							(start -0.2794 0.1778)
							(mid -0.249642 0.249642)
							(end -0.1778 0.2794)
						)
						(arc
							(start 0.1778 0.2794)
							(mid 0.249642 0.249642)
							(end 0.2794 0.1778)
						)
						(arc
							(start 0.2794 -0.1778)
							(mid 0.249642 -0.249642)
							(end 0.1778 -0.2794)
						)
					)
					(width 0)
					(fill yes)
				)
			)
		)
		(pad "2" smd custom
			(at 0 0.4445 180)
			(size 0.1397 0.1397)
			(layers "F.Cu" "F.Mask" "F.Paste")
			(net "GND")
			(options
				(clearance outline)
				(anchor circle)
			)
			(primitives
				(gr_poly
					(pts
						(arc
							(start -0.1778 -0.2794)
							(mid -0.249642 -0.249642)
							(end -0.2794 -0.1778)
						)
						(arc
							(start -0.2794 0.1778)
							(mid -0.249642 0.249642)
							(end -0.1778 0.2794)
						)
						(arc
							(start 0.1778 0.2794)
							(mid 0.249642 0.249642)
							(end 0.2794 0.1778)
						)
						(arc
							(start 0.2794 -0.1778)
							(mid 0.249642 -0.249642)
							(end 0.1778 -0.2794)
						)
					)
					(width 0)
					(fill yes)
				)
			)
		)
	)
	(footprint ""
		(layer "F.Cu")
		(at 191.516 -48.387)
		(property "Reference" "R652"
			(at 0 0 0)
			(layer "F.SilkS")
			(hide yes)
			(effects
				(font
					(size 1.27 1.27)
				)
			)
		)
		(property "Value" "10KR2F-2-GP"
			(at 0.064008 -3.993896 0)
			(unlocked yes)
			(layer "F.Fab")
			(hide yes)
			(effects
				(font
					(size 1.016 1.016)
					(thickness 0.1524)
				)
			)
		)
		(property "Device Type" "R402H16"
			(at 0.064008 -5.517896 0)
			(unlocked yes)
			(layer "F.Fab")
			(hide yes)
			(effects
				(font
					(size 1.016 1.016)
					(thickness 0.1524)
				)
			)
		)
		(duplicate_pad_numbers_are_jumpers no)
		(fp_line
			(start -0.508 -0.9398)
			(end -0.508 0.9398)
			(stroke
				(width 0.1524)
				(type default)
			)
			(layer "F.SilkS")
		)
		(fp_line
			(start 0.508 -0.9398)
			(end -0.508 -0.9398)
			(stroke
				(width 0.1524)
				(type default)
			)
			(layer "F.SilkS")
		)
		(fp_rect
			(start -0.508 0.9398)
			(end 0.508 -0.9398)
			(stroke
				(width 0)
				(type default)
			)
			(fill no)
			(layer "F.CrtYd")
		)
		(fp_rect
			(start -0.508 0.9398)
			(end 0.508 -0.9398)
			(stroke
				(width 0)
				(type default)
			)
			(fill no)
			(layer "F.Fab")
		)
		(pad "1" smd custom
			(at 0 -0.4445)
			(size 0.1397 0.1397)
			(layers "F.Cu" "F.Mask" "F.Paste")
			(net "LSI_SCAN_EN")
			(options
				(clearance outline)
				(anchor circle)
			)
			(primitives
				(gr_poly
					(pts
						(arc
							(start -0.1778 -0.2794)
							(mid -0.249642 -0.249642)
							(end -0.2794 -0.1778)
						)
						(arc
							(start -0.2794 0.1778)
							(mid -0.249642 0.249642)
							(end -0.1778 0.2794)
						)
						(arc
							(start 0.1778 0.2794)
							(mid 0.249642 0.249642)
							(end 0.2794 0.1778)
						)
						(arc
							(start 0.2794 -0.1778)
							(mid 0.249642 -0.249642)
							(end 0.1778 -0.2794)
						)
					)
					(width 0)
					(fill yes)
				)
			)
		)
		(pad "2" smd custom
			(at 0 0.4445)
			(size 0.1397 0.1397)
			(layers "F.Cu" "F.Mask" "F.Paste")
			(net "GND")
			(options
				(clearance outline)
				(anchor circle)
			)
			(primitives
				(gr_poly
					(pts
						(arc
							(start -0.1778 -0.2794)
							(mid -0.249642 -0.249642)
							(end -0.2794 -0.1778)
						)
						(arc
							(start -0.2794 0.1778)
							(mid -0.249642 0.249642)
							(end -0.1778 0.2794)
						)
						(arc
							(start 0.1778 0.2794)
							(mid 0.249642 0.249642)
							(end 0.2794 0.1778)
						)
						(arc
							(start 0.2794 -0.1778)
							(mid 0.249642 -0.249642)
							(end 0.1778 -0.2794)
						)
					)
					(width 0)
					(fill yes)
				)
			)
		)
	)
	(footprint ""
		(layer "F.Cu")
		(at 98.622866 -148.727922 -90)
		(property "Reference" "R35"
			(at 0 0 270)
			(layer "F.SilkS")
			(hide yes)
			(effects
				(font
					(size 1.27 1.27)
				)
			)
		)
		(property "Value" "4K7R2F-GP"
			(at 0.064008 -3.993896 270)
			(unlocked yes)
			(layer "F.Fab")
			(hide yes)
			(effects
				(font
					(size 1.016 1.016)
					(thickness 0.1524)
				)
			)
		)
		(property "Device Type" "R402H16"
			(at 0.064008 -5.517896 270)
			(unlocked yes)
			(layer "F.Fab")
			(hide yes)
			(effects
				(font
					(size 1.016 1.016)
					(thickness 0.1524)
				)
			)
		)
		(duplicate_pad_numbers_are_jumpers no)
		(fp_line
			(start -0.508 -0.9398)
			(end -0.508 0.9398)
			(stroke
				(width 0.1524)
				(type default)
			)
			(layer "F.SilkS")
		)
		(fp_line
			(start 0.508 -0.9398)
			(end -0.508 -0.9398)
			(stroke
				(width 0.1524)
				(type default)
			)
			(layer "F.SilkS")
		)
		(fp_rect
			(start -0.508 0.9398)
			(end 0.508 -0.9398)
			(stroke
				(width 0)
				(type default)
			)
			(fill no)
			(layer "F.CrtYd")
		)
		(fp_rect
			(start -0.508 0.9398)
			(end 0.508 -0.9398)
			(stroke
				(width 0)
				(type default)
			)
			(fill no)
			(layer "F.Fab")
		)
		(pad "1" smd custom
			(at 0 -0.4445 270)
			(size 0.1397 0.1397)
			(layers "F.Cu" "F.Mask" "F.Paste")
			(net "P3V3_STBY")
			(options
				(clearance outline)
				(anchor circle)
			)
			(primitives
				(gr_poly
					(pts
						(arc
							(start -0.1778 -0.2794)
							(mid -0.249642 -0.249642)
							(end -0.2794 -0.1778)
						)
						(arc
							(start -0.2794 0.1778)
							(mid -0.249642 0.249642)
							(end -0.1778 0.2794)
						)
						(arc
							(start 0.1778 0.2794)
							(mid 0.249642 0.249642)
							(end 0.2794 0.1778)
						)
						(arc
							(start 0.2794 -0.1778)
							(mid 0.249642 -0.249642)
							(end 0.1778 -0.2794)
						)
					)
					(width 0)
					(fill yes)
				)
			)
		)
		(pad "2" smd custom
			(at 0 0.4445 270)
			(size 0.1397 0.1397)
			(layers "F.Cu" "F.Mask" "F.Paste")
			(net "USB_EN_3")
			(options
				(clearance outline)
				(anchor circle)
			)
			(primitives
				(gr_poly
					(pts
						(arc
							(start -0.1778 -0.2794)
							(mid -0.249642 -0.249642)
							(end -0.2794 -0.1778)
						)
						(arc
							(start -0.2794 0.1778)
							(mid -0.249642 0.249642)
							(end -0.1778 0.2794)
						)
						(arc
							(start 0.1778 0.2794)
							(mid 0.249642 0.249642)
							(end 0.2794 0.1778)
						)
						(arc
							(start 0.2794 -0.1778)
							(mid 0.249642 -0.249642)
							(end 0.1778 -0.2794)
						)
					)
					(width 0)
					(fill yes)
				)
			)
		)
	)
	(footprint ""
		(layer "F.Cu")
		(at 145.6944 -14.9352)
		(property "Reference" "Q205"
			(at 0 0 0)
			(layer "F.SilkS")
			(hide yes)
			(effects
				(font
					(size 1.27 1.27)
				)
			)
		)
		(property "Value" "SSM6P39TU-GP"
			(at 0.0508 -11.5824 0)
			(unlocked yes)
			(layer "F.Fab")
			(hide yes)
			(effects
				(font
					(size 1.016 1.016)
					(thickness 0.1524)
				)
			)
		)
		(property "Device Type" "UMT6H30"
			(at 0.0508 -13.1572 0)
			(unlocked yes)
			(layer "F.Fab")
			(hide yes)
			(effects
				(font
					(size 1.016 1.016)
					(thickness 0.1524)
				)
			)
		)
		(duplicate_pad_numbers_are_jumpers no)
		(fp_line
			(start -1.27 -0.36449)
			(end -1.27 0.36449)
			(stroke
				(width 0.1524)
				(type default)
			)
			(layer "F.SilkS")
		)
		(fp_line
			(start -1.27 -0.36449)
			(end 1.524 -0.36449)
			(stroke
				(width 0.1524)
				(type default)
			)
			(layer "F.SilkS")
		)
		(fp_line
			(start 1.09347 0)
			(end 1.45796 0.36449)
			(stroke
				(width 0.1524)
				(type default)
			)
			(layer "F.SilkS")
		)
		(fp_line
			(start 1.45796 -0.36449)
			(end 1.09347 0)
			(stroke
				(width 0.1524)
				(type default)
			)
			(layer "F.SilkS")
		)
		(fp_line
			(start 1.524 -0.36449)
			(end 1.45796 -0.36449)
			(stroke
				(width 0.1524)
				(type default)
			)
			(layer "F.SilkS")
		)
		(fp_line
			(start 1.524 -0.36449)
			(end 1.524 -1.82245)
			(stroke
				(width 0.508)
				(type default)
			)
			(layer "F.SilkS")
		)
		(fp_line
			(start 1.524 -0.36449)
			(end 1.524 0.36449)
			(stroke
				(width 0.1524)
				(type default)
			)
			(layer "F.SilkS")
		)
		(fp_line
			(start 1.524 0.36449)
			(end -1.27 0.36449)
			(stroke
				(width 0.1524)
				(type default)
			)
			(layer "F.SilkS")
		)
		(fp_poly
			(pts
				(xy -0.65024 0.36449) (xy -0.65024 -0.36449) (xy 0.65024 -0.36449) (xy 0.65024 0.36449)
			)
			(stroke
				(width 0)
				(type default)
			)
			(fill yes)
			(layer "F.SilkS")
		)
		(fp_poly
			(pts
				(xy 1.016 -1.0668) (xy 1.016 1.0668) (xy -1.016 1.0668) (xy -1.016 -1.0668)
			)
			(stroke
				(width 0)
				(type default)
			)
			(fill no)
			(layer "F.CrtYd")
		)
		(fp_poly
			(pts
				(xy -1.524 1.905) (xy 1.524 1.905) (xy 1.524 -1.06426) (xy 1.016 -1.06426) (xy 1.016 1.0668) (xy -1.016 1.0668)
				(xy -1.016 -1.0668) (xy 1.524 -1.0668) (xy 1.524 -1.905) (xy -1.524 -1.905)
			)
			(stroke
				(width 0)
				(type default)
			)
			(fill no)
			(layer "F.CrtYd")
		)
		(fp_poly
			(pts
				(xy -1.524 -1.905) (xy -1.524 1.905) (xy 1.524 1.905) (xy 1.524 -1.905)
			)
			(stroke
				(width 0)
				(type default)
			)
			(fill no)
			(layer "F.Fab")
		)
		(pad "1" smd rect
			(at 0.65024 -1.02489)
			(size 0.4064 0.8128)
			(layers "F.Cu" "F.Mask" "F.Paste")
			(net "P3V3_STBY")
		)
		(pad "2" smd rect
			(at 0 -1.02489)
			(size 0.4064 0.8128)
			(layers "F.Cu" "F.Mask" "F.Paste")
			(net "EXT2_LED_YELLOW_G1")
		)
		(pad "3" smd rect
			(at -0.65024 -1.02489)
			(size 0.4064 0.8128)
			(layers "F.Cu" "F.Mask" "F.Paste")
			(net "EXT2_LED_BLUE_D")
		)
		(pad "4" smd rect
			(at -0.65024 1.02489)
			(size 0.4064 0.8128)
			(layers "F.Cu" "F.Mask" "F.Paste")
			(net "P5V_STBY")
		)
		(pad "5" smd rect
			(at 0 1.02489)
			(size 0.4064 0.8128)
			(layers "F.Cu" "F.Mask" "F.Paste")
			(net "EXT2_LED_BLUE_G2")
		)
		(pad "6" smd rect
			(at 0.65024 1.02489)
			(size 0.4064 0.8128)
			(layers "F.Cu" "F.Mask" "F.Paste")
			(net "EXT2_LED_YELLOW_D1")
		)
	)
)
